(kicad_pcb
	(version 20260206)
	(generator "pcbnew")
	(generator_version "10.0")
	(general
		(thickness 1.6)
		(legacy_teardrops no)
	)
	(paper "A4")
	(title_block
		(title "04192023_DAF0TMB3IC0_F0TG_MB_C_brd_V02_OCP.brd")
		(comment 1 "Grand Teton / footprints 35-42 of 8354")
	)
	(layers
		(0 "F.Cu" signal "TOP")
		(4 "In1.Cu" signal "GND")
		(6 "In2.Cu" signal "IN1")
		(8 "In3.Cu" signal "GND1")
		(10 "In4.Cu" signal "IN2")
		(12 "In5.Cu" signal "GND2")
		(14 "In6.Cu" signal "IN3")
		(16 "In7.Cu" signal "GND3")
		(18 "In8.Cu" signal "VCC")
		(20 "In9.Cu" signal "VCC1")
		(22 "In10.Cu" signal "GND4")
		(24 "In11.Cu" signal "IN4")
		(26 "In12.Cu" signal "GND5")
		(28 "In13.Cu" signal "IN5")
		(30 "In14.Cu" signal "GND6")
		(32 "In15.Cu" signal "IN6")
		(34 "In16.Cu" signal "GND7")
		(2 "B.Cu" signal "BOTTOM")
		(9 "F.Adhes" user "F.Adhesive")
		(11 "B.Adhes" user "B.Adhesive")
		(13 "F.Paste" user "Package Geometry/Pastemask Top")
		(15 "B.Paste" user "Package Geometry/Pastemask Bottom")
		(5 "F.SilkS" user "Ref Des/Silkscreen Top")
		(7 "B.SilkS" user "Ref Des/Silkscreen Bottom")
		(1 "F.Mask" user "Board Geometry/Soldermask Top")
		(3 "B.Mask" user "Board Geometry/Soldermask Bottom")
		(17 "Dwgs.User" user "User.Drawings")
		(19 "Cmts.User" user "User.Comments")
		(21 "Eco1.User" user "User.Eco1")
		(23 "Eco2.User" user "User.Eco2")
		(25 "Edge.Cuts" user "Board Geometry/Outline")
		(27 "Margin" user)
		(31 "F.CrtYd" user "Package Geometry/Place Bound Top")
		(29 "B.CrtYd" user "Package Geometry/Place Bound Bottom")
		(35 "F.Fab" user "Ref Des/Assembly Top")
		(33 "B.Fab" user "Ref Des/Assembly Bottom")
	)
	(footprint ""
		(layer "F.Cu")
		(at 336.622644 -383.88163 -90)
		(property "Reference" "C957"
			(at 0 0 270)
			(layer "F.SilkS")
			(hide yes)
			(effects
				(font
					(size 1.27 1.27)
				)
			)
		)
		(property "Value" ""
			(at 0 0 270)
			(layer "F.Fab")
			(effects
				(font
					(size 1.27 1.27)
				)
			)
		)
		(duplicate_pad_numbers_are_jumpers no)
		(fp_line
			(start -0.299974 0.150114)
			(end -0.299974 -0.150114)
			(stroke
				(width 0.1)
				(type default)
			)
			(layer "F.Fab")
		)
		(fp_line
			(start 0.299974 0.150114)
			(end -0.299974 0.150114)
			(stroke
				(width 0.1)
				(type default)
			)
			(layer "F.Fab")
		)
		(fp_line
			(start -0.299974 -0.150114)
			(end 0.299974 -0.150114)
			(stroke
				(width 0.1)
				(type default)
			)
			(layer "F.Fab")
		)
		(fp_line
			(start 0.299974 -0.150114)
			(end 0.299974 0.150114)
			(stroke
				(width 0.1)
				(type default)
			)
			(layer "F.Fab")
		)
		(pad "1" smd rect
			(at -0.2667 0 270)
			(size 0.3048 0.381)
			(layers "F.Cu" "F.Mask" "F.Paste")
			(net "P5E_CPU0_P1_TX_C_DP<4>")
		)
		(pad "2" smd rect
			(at 0.2667 0 270)
			(size 0.3048 0.381)
			(layers "F.Cu" "F.Mask" "F.Paste")
			(net "P5E_CPU0_P1_TX_DP<4>")
		)
	)
	(footprint ""
		(layer "F.Cu")
		(at 66.42862 -394.78458 90)
		(property "Reference" "R699"
			(at 0 0 90)
			(layer "F.SilkS")
			(hide yes)
			(effects
				(font
					(size 1.27 1.27)
				)
			)
		)
		(property "Value" ""
			(at 0 0 90)
			(layer "F.Fab")
			(effects
				(font
					(size 1.27 1.27)
				)
			)
		)
		(duplicate_pad_numbers_are_jumpers no)
		(fp_line
			(start 0.32512 -0.175006)
			(end 0.32512 0.175006)
			(stroke
				(width 0.1)
				(type default)
			)
			(layer "F.Fab")
		)
		(fp_line
			(start -0.32512 -0.175006)
			(end 0.32512 -0.175006)
			(stroke
				(width 0.1)
				(type default)
			)
			(layer "F.Fab")
		)
		(fp_line
			(start 0.32512 0.175006)
			(end -0.32512 0.175006)
			(stroke
				(width 0.1)
				(type default)
			)
			(layer "F.Fab")
		)
		(fp_line
			(start -0.32512 0.175006)
			(end -0.32512 -0.175006)
			(stroke
				(width 0.1)
				(type default)
			)
			(layer "F.Fab")
		)
		(pad "1" smd rect
			(at -0.2667 0 90)
			(size 0.3048 0.381)
			(layers "F.Cu" "F.Mask" "F.Paste")
			(net "P1V8_CPU1_RT_1D")
		)
		(pad "2" smd rect
			(at 0.2667 0 270)
			(size 0.3048 0.381)
			(layers "F.Cu" "F.Mask" "F.Paste")
			(net "RT_CPU1_P0_VQPS")
		)
	)
	(footprint ""
		(layer "F.Cu")
		(at 133.223 -112.268)
		(property "Reference" "U8008"
			(at -1.405382 -3.298444 0)
			(unlocked yes)
			(layer "F.SilkS")
			(effects
				(font
					(size 0.7874 0.5842)
					(thickness 0.1524)
				)
			)
		)
		(property "Value" ""
			(at 0 0 0)
			(layer "F.Fab")
			(effects
				(font
					(size 1.27 1.27)
				)
			)
		)
		(duplicate_pad_numbers_are_jumpers no)
		(fp_line
			(start -2.032 -1.549908)
			(end -0.508 -1.549908)
			(stroke
				(width 0.1524)
				(type default)
			)
			(layer "F.SilkS")
		)
		(fp_line
			(start -2.032 1.549908)
			(end -2.032 -1.549908)
			(stroke
				(width 0.1524)
				(type default)
			)
			(layer "F.SilkS")
		)
		(fp_line
			(start -0.508 -1.549908)
			(end 0 -0.762)
			(stroke
				(width 0.1524)
				(type default)
			)
			(layer "F.SilkS")
		)
		(fp_line
			(start 0 -0.762)
			(end 0.508 -1.549908)
			(stroke
				(width 0.1524)
				(type default)
			)
			(layer "F.SilkS")
		)
		(fp_line
			(start 0.508 -1.549908)
			(end 2.032 -1.549908)
			(stroke
				(width 0.1524)
				(type default)
			)
			(layer "F.SilkS")
		)
		(fp_line
			(start 2.032 -1.549908)
			(end 2.032 1.549908)
			(stroke
				(width 0.1524)
				(type default)
			)
			(layer "F.SilkS")
		)
		(fp_line
			(start 2.032 1.549908)
			(end -2.032 1.549908)
			(stroke
				(width 0.1524)
				(type default)
			)
			(layer "F.SilkS")
		)
		(fp_poly
			(pts
				(xy -2.78003 -2.518918) (xy -3.441192 -1.74752) (xy -2.339086 -1.47193)
			)
			(stroke
				(width 0)
				(type default)
			)
			(fill yes)
			(layer "F.SilkS")
		)
		(fp_line
			(start -0.849884 -1.549908)
			(end 0.849884 -1.549908)
			(stroke
				(width 0.1)
				(type default)
			)
			(layer "F.Fab")
		)
		(fp_line
			(start -0.849884 1.549908)
			(end -0.849884 -1.549908)
			(stroke
				(width 0.1)
				(type default)
			)
			(layer "F.Fab")
		)
		(fp_line
			(start 0.849884 -1.549908)
			(end 0.849884 1.549908)
			(stroke
				(width 0.1)
				(type default)
			)
			(layer "F.Fab")
		)
		(fp_line
			(start 0.849884 1.549908)
			(end -0.849884 1.549908)
			(stroke
				(width 0.1)
				(type default)
			)
			(layer "F.Fab")
		)
		(fp_poly
			(pts
				(xy -3.2004 -1.45796) (xy -3.2004 -0.44196) (xy -2.1844 -0.94996)
			)
			(stroke
				(width 0)
				(type default)
			)
			(fill yes)
			(layer "F.Fab")
		)
		(pad "1" smd rect
			(at -1.35001 -0.94996 270)
			(size 0.6096 1.0668)
			(layers "F.Cu" "F.Mask" "F.Paste")
			(net "UV_ADR_P2V5_COMP")
		)
		(pad "2" smd rect
			(at -1.35001 0 270)
			(size 0.6096 1.0668)
			(layers "F.Cu" "F.Mask" "F.Paste")
			(net "GND")
		)
		(pad "3" smd rect
			(at -1.35001 0.94996 270)
			(size 0.6096 1.0668)
			(layers "F.Cu" "F.Mask" "F.Paste")
			(net "P12V_AUX_UV_ADR_TRIGGER")
		)
		(pad "4" smd rect
			(at 1.35001 0.94996 270)
			(size 0.6096 1.0668)
			(layers "F.Cu" "F.Mask" "F.Paste")
			(net "FM_UV_ADR_TRIGGER_N_R2")
		)
		(pad "5" smd rect
			(at 1.35001 -0.94996 270)
			(size 0.6096 1.0668)
			(layers "F.Cu" "F.Mask" "F.Paste")
			(net "P12V_AUX")
		)
	)
	(footprint ""
		(layer "F.Cu")
		(at 24.923496 -344.986864 90)
		(property "Reference" "PR491"
			(at 0 0 90)
			(layer "F.SilkS")
			(hide yes)
			(effects
				(font
					(size 1.27 1.27)
				)
			)
		)
		(property "Value" ""
			(at 0 0 90)
			(layer "F.Fab")
			(effects
				(font
					(size 1.27 1.27)
				)
			)
		)
		(duplicate_pad_numbers_are_jumpers no)
		(fp_line
			(start 0.7874 -0.4064)
			(end 0.7874 0.4064)
			(stroke
				(width 0.1524)
				(type default)
			)
			(layer "F.SilkS")
		)
		(fp_line
			(start -0.7874 -0.4064)
			(end 0.7874 -0.4064)
			(stroke
				(width 0.1524)
				(type default)
			)
			(layer "F.SilkS")
		)
		(fp_line
			(start 0.7874 0.4064)
			(end -0.7874 0.4064)
			(stroke
				(width 0.1524)
				(type default)
			)
			(layer "F.SilkS")
		)
		(fp_line
			(start -0.7874 0.4064)
			(end -0.7874 -0.4064)
			(stroke
				(width 0.1524)
				(type default)
			)
			(layer "F.SilkS")
		)
		(fp_line
			(start -0.12065 -0.305054)
			(end -0.12065 -0.2794)
			(stroke
				(width 0.1)
				(type default)
			)
			(layer "F.Fab")
		)
		(fp_line
			(start -0.67945 -0.305054)
			(end -0.12065 -0.305054)
			(stroke
				(width 0.1)
				(type default)
			)
			(layer "F.Fab")
		)
		(fp_line
			(start 0.67945 -0.3048)
			(end 0.67945 0.3048)
			(stroke
				(width 0.1)
				(type default)
			)
			(layer "F.Fab")
		)
		(fp_line
			(start 0.12065 -0.3048)
			(end 0.67945 -0.3048)
			(stroke
				(width 0.1)
				(type default)
			)
			(layer "F.Fab")
		)
		(fp_line
			(start 0.12065 -0.2794)
			(end 0.12065 -0.3048)
			(stroke
				(width 0.1)
				(type default)
			)
			(layer "F.Fab")
		)
		(fp_line
			(start -0.12065 -0.2794)
			(end 0.12065 -0.2794)
			(stroke
				(width 0.1)
				(type default)
			)
			(layer "F.Fab")
		)
		(fp_line
			(start 0.120396 0.2794)
			(end -0.12065 0.2794)
			(stroke
				(width 0.1)
				(type default)
			)
			(layer "F.Fab")
		)
		(fp_line
			(start -0.12065 0.2794)
			(end -0.12065 0.3048)
			(stroke
				(width 0.1)
				(type default)
			)
			(layer "F.Fab")
		)
		(fp_line
			(start 0.67945 0.3048)
			(end 0.120396 0.3048)
			(stroke
				(width 0.1)
				(type default)
			)
			(layer "F.Fab")
		)
		(fp_line
			(start 0.120396 0.3048)
			(end 0.120396 0.2794)
			(stroke
				(width 0.1)
				(type default)
			)
			(layer "F.Fab")
		)
		(fp_line
			(start -0.12065 0.3048)
			(end -0.67945 0.3048)
			(stroke
				(width 0.1)
				(type default)
			)
			(layer "F.Fab")
		)
		(fp_line
			(start -0.67945 0.3048)
			(end -0.67945 -0.305054)
			(stroke
				(width 0.1)
				(type default)
			)
			(layer "F.Fab")
		)
		(pad "1" smd circle
			(at -0.40005 0 90)
			(size 0 0)
			(layers "F.Cu" "F.Mask" "F.Paste")
			(net "SW_PVDDIO_P1_SW4_RC")
		)
		(pad "2" smd circle
			(at 0.40005 0 90)
			(size 0 0)
			(layers "F.Cu" "F.Mask" "F.Paste")
			(net "GND")
		)
	)
	(footprint ""
		(layer "F.Cu")
		(at 90.563954 -192.038732 180)
		(property "Reference" "PL29"
			(at -14.231112 3.341878 90)
			(unlocked yes)
			(layer "F.SilkS")
			(effects
				(font
					(size 0.7874 0.5842)
					(thickness 0.1524)
				)
				(justify left)
			)
		)
		(property "Value" ""
			(at 0 0 180)
			(layer "F.Fab")
			(effects
				(font
					(size 1.27 1.27)
				)
			)
		)
		(duplicate_pad_numbers_are_jumpers no)
		(fp_line
			(start 3.750056 5.500116)
			(end 3.750056 -5.500116)
			(stroke
				(width 0.1524)
				(type default)
			)
			(layer "F.SilkS")
		)
		(fp_line
			(start 3.750056 -5.500116)
			(end 2.393442 -5.500116)
			(stroke
				(width 0.1524)
				(type default)
			)
			(layer "F.SilkS")
		)
		(fp_line
			(start 2.393442 5.500116)
			(end 3.750056 5.500116)
			(stroke
				(width 0.1524)
				(type default)
			)
			(layer "F.SilkS")
		)
		(fp_line
			(start -2.393442 5.500116)
			(end -3.750056 5.500116)
			(stroke
				(width 0.1524)
				(type default)
			)
			(layer "F.SilkS")
		)
		(fp_line
			(start -3.750056 5.500116)
			(end -3.750056 -5.500116)
			(stroke
				(width 0.1524)
				(type default)
			)
			(layer "F.SilkS")
		)
		(fp_line
			(start -3.750056 -5.500116)
			(end -2.393442 -5.500116)
			(stroke
				(width 0.1524)
				(type default)
			)
			(layer "F.SilkS")
		)
		(fp_poly
			(pts
				(xy -3.9116 -4.249928) (xy -4.445 -3.983228) (xy -4.445 -4.516628)
			)
			(stroke
				(width 0)
				(type default)
			)
			(fill yes)
			(layer "F.SilkS")
		)
		(fp_line
			(start 3.750056 5.500116)
			(end 3.750056 -5.500116)
			(stroke
				(width 0.1)
				(type default)
			)
			(layer "F.Fab")
		)
		(fp_line
			(start 3.750056 -5.500116)
			(end -3.750056 -5.500116)
			(stroke
				(width 0.1)
				(type default)
			)
			(layer "F.Fab")
		)
		(fp_line
			(start -3.750056 5.500116)
			(end 3.750056 5.500116)
			(stroke
				(width 0.1)
				(type default)
			)
			(layer "F.Fab")
		)
		(fp_line
			(start -3.750056 -5.500116)
			(end -3.750056 5.500116)
			(stroke
				(width 0.1)
				(type default)
			)
			(layer "F.Fab")
		)
		(fp_poly
			(pts
				(xy -4.9276 -4.757928) (xy -4.9276 -3.741928) (xy -3.9116 -4.249928)
			)
			(stroke
				(width 0)
				(type default)
			)
			(fill yes)
			(layer "F.Fab")
		)
		(pad "1" smd rect
			(at 0 -4.249928 90)
			(size 2.413 4.5212)
			(layers "F.Cu" "F.Mask" "F.Paste")
			(net "SW_PVDDCR_CPU0_P1_SW2")
		)
		(pad "2" smd rect
			(at 0 -1.175004 90)
			(size 1.3716 4.5212)
			(layers "F.Cu" "F.Mask" "F.Paste")
			(net "IND_CPU0_P1_CPL1")
		)
		(pad "3" smd rect
			(at 0 1.175004 90)
			(size 1.3716 4.5212)
			(layers "F.Cu" "F.Mask" "F.Paste")
			(net "IND_CPU0_P1_CPL2")
		)
		(pad "4" smd rect
			(at 0 4.249928 90)
			(size 2.413 4.5212)
			(layers "F.Cu" "F.Mask" "F.Paste")
			(net "PVDDCR_CPU0_P1")
		)
	)
	(footprint ""
		(layer "F.Cu")
		(at 163.4236 -437.423052)
		(property "Reference" "R3429"
			(at 0 0 0)
			(layer "F.SilkS")
			(hide yes)
			(effects
				(font
					(size 1.27 1.27)
				)
			)
		)
		(property "Value" ""
			(at 0 0 0)
			(layer "F.Fab")
			(effects
				(font
					(size 1.27 1.27)
				)
			)
		)
		(duplicate_pad_numbers_are_jumpers no)
		(fp_line
			(start -0.7874 -0.4064)
			(end 0.7874 -0.4064)
			(stroke
				(width 0.1524)
				(type default)
			)
			(layer "F.SilkS")
		)
		(fp_line
			(start -0.7874 0.4064)
			(end -0.7874 -0.4064)
			(stroke
				(width 0.1524)
				(type default)
			)
			(layer "F.SilkS")
		)
		(fp_line
			(start 0.7874 -0.4064)
			(end 0.7874 0.4064)
			(stroke
				(width 0.1524)
				(type default)
			)
			(layer "F.SilkS")
		)
		(fp_line
			(start 0.7874 0.4064)
			(end -0.7874 0.4064)
			(stroke
				(width 0.1524)
				(type default)
			)
			(layer "F.SilkS")
		)
		(fp_line
			(start -0.67945 -0.305054)
			(end -0.12065 -0.305054)
			(stroke
				(width 0.1)
				(type default)
			)
			(layer "F.Fab")
		)
		(fp_line
			(start -0.67945 0.3048)
			(end -0.67945 -0.305054)
			(stroke
				(width 0.1)
				(type default)
			)
			(layer "F.Fab")
		)
		(fp_line
			(start -0.12065 -0.305054)
			(end -0.12065 -0.2794)
			(stroke
				(width 0.1)
				(type default)
			)
			(layer "F.Fab")
		)
		(fp_line
			(start -0.12065 -0.2794)
			(end 0.12065 -0.2794)
			(stroke
				(width 0.1)
				(type default)
			)
			(layer "F.Fab")
		)
		(fp_line
			(start -0.12065 0.2794)
			(end -0.12065 0.3048)
			(stroke
				(width 0.1)
				(type default)
			)
			(layer "F.Fab")
		)
		(fp_line
			(start -0.12065 0.3048)
			(end -0.67945 0.3048)
			(stroke
				(width 0.1)
				(type default)
			)
			(layer "F.Fab")
		)
		(fp_line
			(start 0.120396 0.2794)
			(end -0.12065 0.2794)
			(stroke
				(width 0.1)
				(type default)
			)
			(layer "F.Fab")
		)
		(fp_line
			(start 0.120396 0.3048)
			(end 0.120396 0.2794)
			(stroke
				(width 0.1)
				(type default)
			)
			(layer "F.Fab")
		)
		(fp_line
			(start 0.12065 -0.3048)
			(end 0.67945 -0.3048)
			(stroke
				(width 0.1)
				(type default)
			)
			(layer "F.Fab")
		)
		(fp_line
			(start 0.12065 -0.2794)
			(end 0.12065 -0.3048)
			(stroke
				(width 0.1)
				(type default)
			)
			(layer "F.Fab")
		)
		(fp_line
			(start 0.67945 -0.3048)
			(end 0.67945 0.3048)
			(stroke
				(width 0.1)
				(type default)
			)
			(layer "F.Fab")
		)
		(fp_line
			(start 0.67945 0.3048)
			(end 0.120396 0.3048)
			(stroke
				(width 0.1)
				(type default)
			)
			(layer "F.Fab")
		)
		(pad "1" smd circle
			(at -0.40005 0)
			(size 0 0)
			(layers "F.Cu" "F.Mask" "F.Paste")
			(net "P3V3_AUX")
		)
		(pad "2" smd circle
			(at 0.40005 0)
			(size 0 0)
			(layers "F.Cu" "F.Mask" "F.Paste")
			(net "GPU_BASE_HMC_READY")
		)
	)
	(footprint ""
		(layer "F.Cu")
		(at 134.162546 -408.517344 -90)
		(property "Reference" "C6705"
			(at 0 0 270)
			(layer "F.SilkS")
			(hide yes)
			(effects
				(font
					(size 1.27 1.27)
				)
			)
		)
		(property "Value" ""
			(at 0 0 270)
			(layer "F.Fab")
			(effects
				(font
					(size 1.27 1.27)
				)
			)
		)
		(duplicate_pad_numbers_are_jumpers no)
		(fp_line
			(start -0.299974 0.150114)
			(end -0.299974 -0.150114)
			(stroke
				(width 0.1)
				(type default)
			)
			(layer "F.Fab")
		)
		(fp_line
			(start 0.299974 0.150114)
			(end -0.299974 0.150114)
			(stroke
				(width 0.1)
				(type default)
			)
			(layer "F.Fab")
		)
		(fp_line
			(start -0.299974 -0.150114)
			(end 0.299974 -0.150114)
			(stroke
				(width 0.1)
				(type default)
			)
			(layer "F.Fab")
		)
		(fp_line
			(start 0.299974 -0.150114)
			(end 0.299974 0.150114)
			(stroke
				(width 0.1)
				(type default)
			)
			(layer "F.Fab")
		)
		(pad "1" smd rect
			(at -0.2667 0 270)
			(size 0.3048 0.381)
			(layers "F.Cu" "F.Mask" "F.Paste")
			(net "P5E_CPU1_P2_TX_BUF_C_DP<6>")
		)
		(pad "2" smd rect
			(at 0.2667 0 270)
			(size 0.3048 0.381)
			(layers "F.Cu" "F.Mask" "F.Paste")
			(net "P5E_CPU1_P2_TX_BUF_DP<6>")
		)
	)
	(footprint ""
		(layer "F.Cu")
		(at 22.479 -358.775 180)
		(property "Reference" "C308"
			(at 0 0 180)
			(layer "F.SilkS")
			(hide yes)
			(effects
				(font
					(size 1.27 1.27)
				)
			)
		)
		(property "Value" ""
			(at 0 0 180)
			(layer "F.Fab")
			(effects
				(font
					(size 1.27 1.27)
				)
			)
		)
		(duplicate_pad_numbers_are_jumpers no)
		(fp_line
			(start 0.7874 0.4064)
			(end -0.7874 0.4064)
			(stroke
				(width 0.1524)
				(type default)
			)
			(layer "F.SilkS")
		)
		(fp_line
			(start 0.7874 -0.4064)
			(end 0.7874 0.4064)
			(stroke
				(width 0.1524)
				(type default)
			)
			(layer "F.SilkS")
		)
		(fp_line
			(start -0.7874 0.4064)
			(end -0.7874 -0.4064)
			(stroke
				(width 0.1524)
				(type default)
			)
			(layer "F.SilkS")
		)
		(fp_line
			(start -0.7874 -0.4064)
			(end 0.7874 -0.4064)
			(stroke
				(width 0.1524)
				(type default)
			)
			(layer "F.SilkS")
		)
		(fp_line
			(start 0.67945 0.3048)
			(end 0.120396 0.3048)
			(stroke
				(width 0.1)
				(type default)
			)
			(layer "F.Fab")
		)
		(fp_line
			(start 0.67945 -0.3048)
			(end 0.67945 0.3048)
			(stroke
				(width 0.1)
				(type default)
			)
			(layer "F.Fab")
		)
		(fp_line
			(start 0.12065 -0.2794)
			(end 0.12065 -0.3048)
			(stroke
				(width 0.1)
				(type default)
			)
			(layer "F.Fab")
		)
		(fp_line
			(start 0.12065 -0.3048)
			(end 0.67945 -0.3048)
			(stroke
				(width 0.1)
				(type default)
			)
			(layer "F.Fab")
		)
		(fp_line
			(start 0.120396 0.3048)
			(end 0.120396 0.2794)
			(stroke
				(width 0.1)
				(type default)
			)
			(layer "F.Fab")
		)
		(fp_line
			(start 0.120396 0.2794)
			(end -0.12065 0.2794)
			(stroke
				(width 0.1)
				(type default)
			)
			(layer "F.Fab")
		)
		(fp_line
			(start -0.12065 0.3048)
			(end -0.67945 0.3048)
			(stroke
				(width 0.1)
				(type default)
			)
			(layer "F.Fab")
		)
		(fp_line
			(start -0.12065 0.2794)
			(end -0.12065 0.3048)
			(stroke
				(width 0.1)
				(type default)
			)
			(layer "F.Fab")
		)
		(fp_line
			(start -0.12065 -0.2794)
			(end 0.12065 -0.2794)
			(stroke
				(width 0.1)
				(type default)
			)
			(layer "F.Fab")
		)
		(fp_line
			(start -0.12065 -0.305054)
			(end -0.12065 -0.2794)
			(stroke
				(width 0.1)
				(type default)
			)
			(layer "F.Fab")
		)
		(fp_line
			(start -0.67945 0.3048)
			(end -0.67945 -0.305054)
			(stroke
				(width 0.1)
				(type default)
			)
			(layer "F.Fab")
		)
		(fp_line
			(start -0.67945 -0.305054)
			(end -0.12065 -0.305054)
			(stroke
				(width 0.1)
				(type default)
			)
			(layer "F.Fab")
		)
		(pad "1" smd circle
			(at -0.40005 0 180)
			(size 0 0)
			(layers "F.Cu" "F.Mask" "F.Paste")
			(net "SVID_PVDDCR_CPU1_P1_SVTO")
		)
		(pad "2" smd circle
			(at 0.40005 0 180)
			(size 0 0)
			(layers "F.Cu" "F.Mask" "F.Paste")
			(net "GND")
		)
	)
)
